# T6G (Grand Teton) — schematic netlist excerpt (pin names and nets, part order shuffled) for the footprints in the layout excerpt that follows; sources: Cadence DE-HDL packaged netlist, KiCad conversion of 04192023_DAF0TMB3IC0_F0TG_MB_C_brd_V02_OCP.brd

J18  SCONN288_DDR506112002KQ  IO  pkg DDR288S_1-1VXC  page 94
  VIN_BULK0  = P12V_MEM_CPU0
  RFU0  = NC
  VIN_MGMT  = P3V3_AUX
  HSCL  = I3C_SPD_DDRI_CPU0_SCL
  HSDA  = I3C_SPD_DDRI_CPU0_SDA
  VSS0  = GND
  DQ0_A  = M_I_CPU0_SA_DQ<0>
  VSS1  = GND
  DQ1_A  = M_I_CPU0_SA_DQ<1>
  VSS2  = GND
  DQS0_A_T  = M_I_CPU0_SA_DQS_DP<0>
  DQS0_A_C  = M_I_CPU0_SA_DQS_DN<0>
  VSS3  = GND
  DQ4_A  = M_I_CPU0_SA_DQ<4>
  VSS4  = GND
  DQ5_A  = M_I_CPU0_SA_DQ<5>
  VSS5  = GND
  DQ8_A  = M_I_CPU0_SA_DQ<8>
  VSS6  = GND
  DQ9_A  = M_I_CPU0_SA_DQ<9>
  VSS7  = GND
  DQS1_A_T  = M_I_CPU0_SA_DQS_DP<1>
  DQS1_A_C  = M_I_CPU0_SA_DQS_DN<1>
  VSS8  = GND
  DQ12_A  = M_I_CPU0_SA_DQ<12>
  VSS9  = GND
  DQ13_A  = M_I_CPU0_SA_DQ<13>
  VSS10  = GND
  DQ16_A  = M_I_CPU0_SA_DQ<16>
  VSS11  = GND
  DQ17_A  = M_I_CPU0_SA_DQ<17>
  VSS12  = GND
  DQS2_A_T  = M_I_CPU0_SA_DQS_DP<2>
  DQS2_A_C  = M_I_CPU0_SA_DQS_DN<2>
  VSS13  = GND
  DQ20_A  = M_I_CPU0_SA_DQ<20>
  VSS14  = GND
  DQ21_A  = M_I_CPU0_SA_DQ<21>
  VSS15  = GND
  DQ24_A  = M_I_CPU0_SA_DQ<24>
  VSS16  = GND
  DQ25_A  = M_I_CPU0_SA_DQ<25>
  VSS17  = GND
  DQS3_A_T  = M_I_CPU0_SA_DQS_DP<3>
  DQS3_A_C  = M_I_CPU0_SA_DQS_DN<3>
  VSS18  = GND
  DQ28_A  = M_I_CPU0_SA_DQ<28>
  VSS19  = GND
  DQ29_A  = M_I_CPU0_SA_DQ<29>
  VSS20  = GND
  CB0_A  = M_I_CPU0_SA_CB<0>
  VSS21  = GND
  CB1_A  = M_I_CPU0_SA_CB<1>
  VSS22  = GND
  DQS4_A_T  = M_I_CPU0_SA_DQS_DP<4>
  DQS4_A_C  = M_I_CPU0_SA_DQS_DN<4>
  VSS23  = GND
  CB4_A  = M_I_CPU0_SA_CB<4>
  VSS24  = GND
  CB5_A  = M_I_CPU0_SA_CB<5>
  VSS25  = GND
  ALERT_N  = M_I_CPU0_ALERT_N
  VSS26  = GND
  CS0_A_N  = M_I_CPU0_SA_CS_N<0>
  VSS27  = GND
  CA0_A  = M_I_CPU0_SA_CA<0>
  VSS28  = GND
  CA2_A  = M_I_CPU0_SA_CA<2>
  VSS29  = GND
  CA4_A  = M_I_CPU0_SA_CA<4>
  VSS30  = GND
  CA6_A  = M_I_CPU0_SA_CA<6>
  VSS31  = GND
  PAR_A  = M_I_CPU0_SA_PAR
  VSS32  = GND
  CA0_B  = M_I_CPU0_SB_CA<0>
  VSS33  = GND
  CA2_B  = M_I_CPU0_SB_CA<2>
  VSS34  = GND
  CA4_B  = M_I_CPU0_SB_CA<4>
  VSS35  = GND
  CA6_B  = M_I_CPU0_SB_CA<6>
  VSS36  = GND
  CS0_B_N  = M_I_CPU0_SB_CS_N<0>
  VSS37  = GND
  \lbd||rsp_a_n\  = M_I_CPU0_SA_RSP<0>
  \lbs||rsp_b_n\  = M_I_CPU0_SB_RSP<0>
  VSS38  = GND
  CB4_B  = M_I_CPU0_SB_CB<4>
  VSS39  = GND
  CB5_B  = M_I_CPU0_SB_CB<5>
  VSS40  = GND
  \dqs9_b_t||tdqs9_b_t||dbi4_b_n\  = M_I_CPU0_SB_DQS_DP<9>
  \dqs9_b_c||tdqs9_b_c\  = M_I_CPU0_SB_DQS_DN<9>
  VSS41  = GND
  CB0_B  = M_I_CPU0_SB_CB<0>
  VSS42  = GND
  CB1_B  = M_I_CPU0_SB_CB<1>
  VSS43  = GND
  DQ0_B  = M_I_CPU0_SB_DQ<0>
  VSS44  = GND
  DQ1_B  = M_I_CPU0_SB_DQ<1>
  VSS45  = GND
  DQS0_B_T  = M_I_CPU0_SB_DQS_DP<0>
  DQS0_B_C  = M_I_CPU0_SB_DQS_DN<0>
  VSS46  = GND
  DQ4_B  = M_I_CPU0_SB_DQ<4>
  VSS47  = GND
  DQ5_B  = M_I_CPU0_SB_DQ<5>
  VSS48  = GND
  DQ8_B  = M_I_CPU0_SB_DQ<8>
  VSS49  = GND
  DQ9_B  = M_I_CPU0_SB_DQ<9>
  VSS50  = GND
  DQS1_B_T  = M_I_CPU0_SB_DQS_DP<1>
  DQS1_B_C  = M_I_CPU0_SB_DQS_DN<1>
  VSS51  = GND
  DQ12_B  = M_I_CPU0_SB_DQ<12>
  VSS52  = GND
  DQ13_B  = M_I_CPU0_SB_DQ<13>
  VSS53  = GND
  DQ16_B  = M_I_CPU0_SB_DQ<16>
  VSS54  = GND
  DQ17_B  = M_I_CPU0_SB_DQ<17>
  VSS55  = GND
  DQS2_B_T  = M_I_CPU0_SB_DQS_DP<2>
  DQS2_B_C  = M_I_CPU0_SB_DQS_DN<2>
  VSS56  = GND
  DQ20_B  = M_I_CPU0_SB_DQ<20>
  VSS57  = GND
  DQ21_B  = M_I_CPU0_SB_DQ<21>
  VSS58  = GND
  DQ24_B  = M_I_CPU0_SB_DQ<24>
  VSS59  = GND
  DQ25_B  = M_I_CPU0_SB_DQ<25>
  VSS60  = GND
  DQS3_B_T  = M_I_CPU0_SB_DQS_DP<3>
  DQS3_B_C  = M_I_CPU0_SB_DQS_DN<3>
  VSS61  = GND
  DQ28_B  = M_I_CPU0_SB_DQ<28>
  VSS62  = GND
  DQ29_B  = M_I_CPU0_SB_DQ<29>
  VSS63  = GND
  RFU1  = NC
  VIN_BULK1  = P12V_MEM_CPU0
  VIN_BULK2  = P12V_MEM_CPU0
  \pwr_good||fail_n\  = PWRGD_CHI_CPU0_DIMM
  HAS  = PD_CHI_CPU0_DIMM_SAA
  RFU2  = NC
  RFU3  = NC
  VSS64  = GND
  DQ2_A  = M_I_CPU0_SA_DQ<2>
  VSS65  = GND
  DQ3_A  = M_I_CPU0_SA_DQ<3>
  VSS66  = GND
  \dqs5_a_c||tdqs5_a_c||dqs5_a_t||tdqs5_a_t\  = M_I_CPU0_SA_DQS_DN<5>
  \dqs5_a_t||tdqs5_a_t\  = M_I_CPU0_SA_DQS_DP<5>
  VSS67  = GND
  DQ6_A  = M_I_CPU0_SA_DQ<6>
  VSS68  = GND
  DQ7_A  = M_I_CPU0_SA_DQ<7>
  VSS69  = GND
  DQ10_A  = M_I_CPU0_SA_DQ<10>
  VSS70  = GND
  DQ11_A  = M_I_CPU0_SA_DQ<11>
  VSS71  = GND
  \dqs6_a_c||tdqs6_a_c||dqs6_a_t||tdqs6_a_t\  = M_I_CPU0_SA_DQS_DN<6>
  \dqs6_a_t||tdqs6_a_t\  = M_I_CPU0_SA_DQS_DP<6>
  VSS72  = GND
  DQ14_A  = M_I_CPU0_SA_DQ<14>
  VSS73  = GND
  DQ15_A  = M_I_CPU0_SA_DQ<15>
  VSS74  = GND
  DQ18_A  = M_I_CPU0_SA_DQ<18>
  VSS75  = GND
  DQ19_A  = M_I_CPU0_SA_DQ<19>
  VSS76  = GND
  \dqs7_a_c||tdqs7_a_c\  = M_I_CPU0_SA_DQS_DN<7>
  \dqs7_a_t||tdqs7_a_t\  = M_I_CPU0_SA_DQS_DP<7>
  VSS77  = GND
  DQ22_A  = M_I_CPU0_SA_DQ<22>
  VSS78  = GND
  DQ23_A  = M_I_CPU0_SA_DQ<23>
  VSS79  = GND
  DQ26_A  = M_I_CPU0_SA_DQ<26>
  VSS80  = GND
  DQ27_A  = M_I_CPU0_SA_DQ<27>
  VSS81  = GND
  \dqs8_a_c||tdqs8_a_c\  = M_I_CPU0_SA_DQS_DN<8>
  \dqs8_a_t||tdqs8_a_t\  = M_I_CPU0_SA_DQS_DP<8>
  VSS82  = GND
  DQ30_A  = M_I_CPU0_SA_DQ<30>
  VSS83  = GND
  DQ31_A  = M_I_CPU0_SA_DQ<31>
  VSS84  = GND
  CB2_A  = M_I_CPU0_SA_CB<2>
  VSS85  = GND
  CB3_A  = M_I_CPU0_SA_CB<3>
  VSS86  = GND
  \dqs9_a_c||tdqs9_a_c\  = M_I_CPU0_SA_DQS_DN<9>
  \dqs9_a_t||tdqs9_a_t\  = M_I_CPU0_SA_DQS_DP<9>
  VSS87  = GND
  CB6_A  = M_I_CPU0_SA_CB<6>
  VSS88  = GND
  CB7_A  = M_I_CPU0_SA_CB<7>
  VSS89  = GND
  RESET_N  = M_I_CPU0_RESET_N
  VSS90  = GND
  CS1_A_N  = M_I_CPU0_SA_CS_N<1>
  VSS91  = GND
  CA1_A  = M_I_CPU0_SA_CA<1>
  VSS92  = GND
  CA3_A  = M_I_CPU0_SA_CA<3>
  VSS93  = GND
  CA5_A  = M_I_CPU0_SA_CA<5>
  VSS94  = GND
  CK_T  = M_I_CPU0_CLK_DP<0>
  CK_C  = M_I_CPU0_CLK_DN<0>
  VSS95  = GND
  RFU4  = NC
  CA1_B  = M_I_CPU0_SB_CA<1>
  VSS96  = GND
  CA3_B  = M_I_CPU0_SB_CA<3>
  VSS97  = GND
  CA5_B  = M_I_CPU0_SB_CA<5>
  VSS98  = GND
  PAR_B  = M_I_CPU0_SB_PAR
  VSS99  = GND
  CS1_B_N  = M_I_CPU0_SB_CS_N<1>
  VSS100  = GND
  RFU5  = NC
  RFU6  = NC
  VSS101  = GND
  CB6_B  = M_I_CPU0_SB_CB<6>
  VSS102  = GND
  CB7_B  = M_I_CPU0_SB_CB<7>
  VSS103  = GND
  DQS4_B_C  = M_I_CPU0_SB_DQS_DN<4>
  DQS4_B_T  = M_I_CPU0_SB_DQS_DP<4>
  VSS104  = GND
  CB2_B  = M_I_CPU0_SB_CB<2>
  VSS105  = GND
  CB3_B  = M_I_CPU0_SB_CB<3>
  VSS106  = GND
  DQ2_B  = M_I_CPU0_SB_DQ<2>
  VSS107  = GND
  DQ3_B  = M_I_CPU0_SB_DQ<3>
  VSS108  = GND
  \dqs5_b_c||tdqs5_b_c\  = M_I_CPU0_SB_DQS_DN<5>
  \dqs5_b_t||tdqs5_b_t\  = M_I_CPU0_SB_DQS_DP<5>
  VSS109  = GND
  DQ6_B  = M_I_CPU0_SB_DQ<6>
  VSS110  = GND
  DQ7_B  = M_I_CPU0_SB_DQ<7>
  VSS111  = GND
  DQ10_B  = M_I_CPU0_SB_DQ<10>
  VSS112  = GND
  DQ11_B  = M_I_CPU0_SB_DQ<11>
  VSS113  = GND
  \dqs6_b_c||tdqs6_b_c\  = M_I_CPU0_SB_DQS_DN<6>
  \dqs6_b_t||tdqs6_b_t\  = M_I_CPU0_SB_DQS_DP<6>
  VSS114  = GND
  DQ14_B  = M_I_CPU0_SB_DQ<14>
  VSS115  = GND
  DQ15_B  = M_I_CPU0_SB_DQ<15>
  VSS116  = GND
  DQ18_B  = M_I_CPU0_SB_DQ<18>
  VSS117  = GND
  DQ19_B  = M_I_CPU0_SB_DQ<19>
  VSS118  = GND
  \dqs7_b_c||tdqs7_b_c\  = M_I_CPU0_SB_DQS_DN<7>
  \dqs7_b_t||tdqs7_b_t\  = M_I_CPU0_SB_DQS_DP<7>
  VSS119  = GND
  DQ22_B  = M_I_CPU0_SB_DQ<22>
  VSS120  = GND
  DQ23_B  = M_I_CPU0_SB_DQ<23>
  VSS121  = GND
  DQ26_B  = M_I_CPU0_SB_DQ<26>
  VSS122  = GND
  DQ27_B  = M_I_CPU0_SB_DQ<27>
  VSS123  = GND
  \dqs8_b_c||tdqs8_b_c\  = M_I_CPU0_SB_DQS_DN<8>
  \dqs8_b_t||tdqs8_b_t\  = M_I_CPU0_SB_DQS_DP<8>
  VSS124  = GND
  DQ30_B  = M_I_CPU0_SB_DQ<30>
  VSS125  = GND
  DQ31_B  = M_I_CPU0_SB_DQ<31>
  VSS126  = GND
  G1  = GND
  G2  = GND
  G3  = GND

(kicad_pcb
	(version 20260206)
	(generator "pcbnew")
	(generator_version "10.0")
	(general
		(thickness 1.6)
		(legacy_teardrops no)
	)
	(paper "A4")
	(title_block
		(title "04192023_DAF0TMB3IC0_F0TG_MB_C_brd_V02_OCP.brd")
		(comment 1 "Grand Teton / footprint 4761 of 8354 (J18), pads 93-138 of 291")
	)
	(layers
		(0 "F.Cu" signal "TOP")
		(4 "In1.Cu" signal "GND")
		(6 "In2.Cu" signal "IN1")
		(8 "In3.Cu" signal "GND1")
		(10 "In4.Cu" signal "IN2")
		(12 "In5.Cu" signal "GND2")
		(14 "In6.Cu" signal "IN3")
		(16 "In7.Cu" signal "GND3")
		(18 "In8.Cu" signal "VCC")
		(20 "In9.Cu" signal "VCC1")
		(22 "In10.Cu" signal "GND4")
		(24 "In11.Cu" signal "IN4")
		(26 "In12.Cu" signal "GND5")
		(28 "In13.Cu" signal "IN5")
		(30 "In14.Cu" signal "GND6")
		(32 "In15.Cu" signal "IN6")
		(34 "In16.Cu" signal "GND7")
		(2 "B.Cu" signal "BOTTOM")
		(9 "F.Adhes" user "F.Adhesive")
		(11 "B.Adhes" user "B.Adhesive")
		(13 "F.Paste" user "Package Geometry/Pastemask Top")
		(15 "B.Paste" user "Package Geometry/Pastemask Bottom")
		(5 "F.SilkS" user "Ref Des/Silkscreen Top")
		(7 "B.SilkS" user "Ref Des/Silkscreen Bottom")
		(1 "F.Mask" user "Board Geometry/Soldermask Top")
		(3 "B.Mask" user "Board Geometry/Soldermask Bottom")
		(17 "Dwgs.User" user "User.Drawings")
		(19 "Cmts.User" user "User.Comments")
		(21 "Eco1.User" user "User.Eco1")
		(23 "Eco2.User" user "User.Eco2")
		(25 "Edge.Cuts" user "Board Geometry/Outline")
		(27 "Margin" user)
		(31 "F.CrtYd" user "Package Geometry/Place Bound Top")
		(29 "B.CrtYd" user "Package Geometry/Place Bound Bottom")
		(35 "F.Fab" user "Ref Des/Assembly Top")
		(33 "B.Fab" user "Ref Des/Assembly Bottom")
	)
	(footprint ""
		(layer "F.Cu")
		(at 429.506126 -255.560068 180)
		(property "Reference" "J18"
			(at 0.484632 -81.752948 0)
			(unlocked yes)
			(layer "F.SilkS")
			(effects
				(font
					(size 0.7874 0.5842)
					(thickness 0.1524)
				)
			)
		)
		(property "Value" ""
			(at 0 0 180)
			(layer "F.Fab")
			(effects
				(font
					(size 1.27 1.27)
				)
			)
		)
		(duplicate_pad_numbers_are_jumpers no)
		(pad "93" smd rect
			(at -2.050034 19.975068 90)
			(size 0.519938 1.4986)
			(layers "F.Cu" "F.Mask" "F.Paste")
			(net "M_I_CPU0_SB_DQS_DP<9>")
		)
		(pad "94" smd rect
			(at -2.050034 20.824952 90)
			(size 0.519938 1.4986)
			(layers "F.Cu" "F.Mask" "F.Paste")
			(net "M_I_CPU0_SB_DQS_DN<9>")
		)
		(pad "95" smd rect
			(at -2.050034 21.67509 90)
			(size 0.519938 1.4986)
			(layers "F.Cu" "F.Mask" "F.Paste")
			(net "GND")
		)
		(pad "96" smd rect
			(at -2.050034 22.524974 90)
			(size 0.519938 1.4986)
			(layers "F.Cu" "F.Mask" "F.Paste")
			(net "M_I_CPU0_SB_CB<0>")
		)
		(pad "97" smd rect
			(at -2.050034 23.375112 90)
			(size 0.519938 1.4986)
			(layers "F.Cu" "F.Mask" "F.Paste")
			(net "GND")
		)
		(pad "98" smd rect
			(at -2.050034 24.224996 90)
			(size 0.519938 1.4986)
			(layers "F.Cu" "F.Mask" "F.Paste")
			(net "M_I_CPU0_SB_CB<1>")
		)
		(pad "99" smd rect
			(at -2.050034 25.07488 90)
			(size 0.519938 1.4986)
			(layers "F.Cu" "F.Mask" "F.Paste")
			(net "GND")
		)
		(pad "100" smd rect
			(at -2.050034 25.925018 90)
			(size 0.519938 1.4986)
			(layers "F.Cu" "F.Mask" "F.Paste")
			(net "M_I_CPU0_SB_DQ<0>")
		)
		(pad "101" smd rect
			(at -2.050034 26.774902 90)
			(size 0.519938 1.4986)
			(layers "F.Cu" "F.Mask" "F.Paste")
			(net "GND")
		)
		(pad "102" smd rect
			(at -2.050034 27.62504 90)
			(size 0.519938 1.4986)
			(layers "F.Cu" "F.Mask" "F.Paste")
			(net "M_I_CPU0_SB_DQ<1>")
		)
		(pad "103" smd rect
			(at -2.050034 28.474924 90)
			(size 0.519938 1.4986)
			(layers "F.Cu" "F.Mask" "F.Paste")
			(net "GND")
		)
		(pad "104" smd rect
			(at -2.050034 29.325062 90)
			(size 0.519938 1.4986)
			(layers "F.Cu" "F.Mask" "F.Paste")
			(net "M_I_CPU0_SB_DQS_DP<0>")
		)
		(pad "105" smd rect
			(at -2.050034 30.174946 90)
			(size 0.519938 1.4986)
			(layers "F.Cu" "F.Mask" "F.Paste")
			(net "M_I_CPU0_SB_DQS_DN<0>")
		)
		(pad "106" smd rect
			(at -2.050034 31.025084 90)
			(size 0.519938 1.4986)
			(layers "F.Cu" "F.Mask" "F.Paste")
			(net "GND")
		)
		(pad "107" smd rect
			(at -2.050034 31.874968 90)
			(size 0.519938 1.4986)
			(layers "F.Cu" "F.Mask" "F.Paste")
			(net "M_I_CPU0_SB_DQ<4>")
		)
		(pad "108" smd rect
			(at -2.050034 32.725106 90)
			(size 0.519938 1.4986)
			(layers "F.Cu" "F.Mask" "F.Paste")
			(net "GND")
		)
		(pad "109" smd rect
			(at -2.050034 33.57499 90)
			(size 0.519938 1.4986)
			(layers "F.Cu" "F.Mask" "F.Paste")
			(net "M_I_CPU0_SB_DQ<5>")
		)
		(pad "110" smd rect
			(at -2.050034 34.425128 90)
			(size 0.519938 1.4986)
			(layers "F.Cu" "F.Mask" "F.Paste")
			(net "GND")
		)
		(pad "111" smd rect
			(at -2.050034 35.275012 90)
			(size 0.519938 1.4986)
			(layers "F.Cu" "F.Mask" "F.Paste")
			(net "M_I_CPU0_SB_DQ<8>")
		)
		(pad "112" smd rect
			(at -2.050034 36.124896 90)
			(size 0.519938 1.4986)
			(layers "F.Cu" "F.Mask" "F.Paste")
			(net "GND")
		)
		(pad "113" smd rect
			(at -2.050034 36.975034 90)
			(size 0.519938 1.4986)
			(layers "F.Cu" "F.Mask" "F.Paste")
			(net "M_I_CPU0_SB_DQ<9>")
		)
		(pad "114" smd rect
			(at -2.050034 37.824918 90)
			(size 0.519938 1.4986)
			(layers "F.Cu" "F.Mask" "F.Paste")
			(net "GND")
		)
		(pad "115" smd rect
			(at -2.050034 38.675056 90)
			(size 0.519938 1.4986)
			(layers "F.Cu" "F.Mask" "F.Paste")
			(net "M_I_CPU0_SB_DQS_DP<1>")
		)
		(pad "116" smd rect
			(at -2.050034 39.52494 90)
			(size 0.519938 1.4986)
			(layers "F.Cu" "F.Mask" "F.Paste")
			(net "M_I_CPU0_SB_DQS_DN<1>")
		)
		(pad "117" smd rect
			(at -2.050034 40.375078 90)
			(size 0.519938 1.4986)
			(layers "F.Cu" "F.Mask" "F.Paste")
			(net "GND")
		)
		(pad "118" smd rect
			(at -2.050034 41.224962 90)
			(size 0.519938 1.4986)
			(layers "F.Cu" "F.Mask" "F.Paste")
			(net "M_I_CPU0_SB_DQ<12>")
		)
		(pad "119" smd rect
			(at -2.050034 42.0751 90)
			(size 0.519938 1.4986)
			(layers "F.Cu" "F.Mask" "F.Paste")
			(net "GND")
		)
		(pad "120" smd rect
			(at -2.050034 42.924984 90)
			(size 0.519938 1.4986)
			(layers "F.Cu" "F.Mask" "F.Paste")
			(net "M_I_CPU0_SB_DQ<13>")
		)
		(pad "121" smd rect
			(at -2.050034 43.775122 90)
			(size 0.519938 1.4986)
			(layers "F.Cu" "F.Mask" "F.Paste")
			(net "GND")
		)
		(pad "122" smd rect
			(at -2.050034 44.625006 90)
			(size 0.519938 1.4986)
			(layers "F.Cu" "F.Mask" "F.Paste")
			(net "M_I_CPU0_SB_DQ<16>")
		)
		(pad "123" smd rect
			(at -2.050034 45.47489 90)
			(size 0.519938 1.4986)
			(layers "F.Cu" "F.Mask" "F.Paste")
			(net "GND")
		)
		(pad "124" smd rect
			(at -2.050034 46.325028 90)
			(size 0.519938 1.4986)
			(layers "F.Cu" "F.Mask" "F.Paste")
			(net "M_I_CPU0_SB_DQ<17>")
		)
		(pad "125" smd rect
			(at -2.050034 47.174912 90)
			(size 0.519938 1.4986)
			(layers "F.Cu" "F.Mask" "F.Paste")
			(net "GND")
		)
		(pad "126" smd rect
			(at -2.050034 48.02505 90)
			(size 0.519938 1.4986)
			(layers "F.Cu" "F.Mask" "F.Paste")
			(net "M_I_CPU0_SB_DQS_DP<2>")
		)
		(pad "127" smd rect
			(at -2.050034 48.874934 90)
			(size 0.519938 1.4986)
			(layers "F.Cu" "F.Mask" "F.Paste")
			(net "M_I_CPU0_SB_DQS_DN<2>")
		)
		(pad "128" smd rect
			(at -2.050034 49.725072 90)
			(size 0.519938 1.4986)
			(layers "F.Cu" "F.Mask" "F.Paste")
			(net "GND")
		)
		(pad "129" smd rect
			(at -2.050034 50.574956 90)
			(size 0.519938 1.4986)
			(layers "F.Cu" "F.Mask" "F.Paste")
			(net "M_I_CPU0_SB_DQ<20>")
		)
		(pad "130" smd rect
			(at -2.050034 51.425094 90)
			(size 0.519938 1.4986)
			(layers "F.Cu" "F.Mask" "F.Paste")
			(net "GND")
		)
		(pad "131" smd rect
			(at -2.050034 52.274978 90)
			(size 0.519938 1.4986)
			(layers "F.Cu" "F.Mask" "F.Paste")
			(net "M_I_CPU0_SB_DQ<21>")
		)
		(pad "132" smd rect
			(at -2.050034 53.125116 90)
			(size 0.519938 1.4986)
			(layers "F.Cu" "F.Mask" "F.Paste")
			(net "GND")
		)
		(pad "133" smd rect
			(at -2.050034 53.975 90)
			(size 0.519938 1.4986)
			(layers "F.Cu" "F.Mask" "F.Paste")
			(net "M_I_CPU0_SB_DQ<24>")
		)
		(pad "134" smd rect
			(at -2.050034 54.824884 90)
			(size 0.519938 1.4986)
			(layers "F.Cu" "F.Mask" "F.Paste")
			(net "GND")
		)
		(pad "135" smd rect
			(at -2.050034 55.675022 90)
			(size 0.519938 1.4986)
			(layers "F.Cu" "F.Mask" "F.Paste")
			(net "M_I_CPU0_SB_DQ<25>")
		)
		(pad "136" smd rect
			(at -2.050034 56.524906 90)
			(size 0.519938 1.4986)
			(layers "F.Cu" "F.Mask" "F.Paste")
			(net "GND")
		)
		(pad "137" smd rect
			(at -2.050034 57.375044 90)
			(size 0.519938 1.4986)
			(layers "F.Cu" "F.Mask" "F.Paste")
			(net "M_I_CPU0_SB_DQS_DP<3>")
		)
		(pad "138" smd rect
			(at -2.050034 58.224928 90)
			(size 0.519938 1.4986)
			(layers "F.Cu" "F.Mask" "F.Paste")
			(net "M_I_CPU0_SB_DQS_DN<3>")
		)
	)
)
